# BASEBOARD_FAB2 (Tioga Pass) — schematic netlist excerpt (pin names and nets, part order shuffled) for the footprints in the layout excerpt that follows; sources: Cadence DE-HDL packaged netlist, KiCad conversion of Wiwynn_Tioga_Pass_MB.brd

FB3M4  FERRITE  120 FB  pkg SM  page 127 : A = P1V05_PCH_STBY ; B = P1V05_PCH_STBY_ISCLK_PLL
C8L6  CAP_A  47UF 4V 20% X5R  pkg 0603V  page 228 : A = PVDDQ_KLM ; B = GND
C1E6  SC1U10V2KX-4-GP  10%  pkg SMD-BCG6  page 207 : \1\ = P5V_STBY ; \2\ = GND

(kicad_pcb
	(version 20260206)
	(generator "pcbnew")
	(generator_version "10.0")
	(general
		(thickness 1.6)
		(legacy_teardrops no)
	)
	(paper "A4")
	(title_block
		(title "Wiwynn_Tioga_Pass_MB.brd")
		(comment 1 "Tioga Pass / footprints 3756-3758 of 4770")
	)
	(layers
		(0 "F.Cu" signal "TOP")
		(4 "In1.Cu" signal "L2GND")
		(6 "In2.Cu" signal "L3")
		(8 "In3.Cu" signal "L4GND")
		(10 "In4.Cu" signal "L5")
		(12 "In5.Cu" signal "L6GND")
		(14 "In6.Cu" signal "L7VCC")
		(16 "In7.Cu" signal "L8VCC")
		(18 "In8.Cu" signal "L9GND")
		(20 "In9.Cu" signal "L10")
		(22 "In10.Cu" signal "L11GND")
		(24 "In11.Cu" signal "L12")
		(26 "In12.Cu" signal "L13GND")
		(2 "B.Cu" signal "BOTTOM")
		(9 "F.Adhes" user "F.Adhesive")
		(11 "B.Adhes" user "B.Adhesive")
		(13 "F.Paste" user "Package Geometry/Pastemask Top")
		(15 "B.Paste" user "Package Geometry/Pastemask Bottom")
		(5 "F.SilkS" user "Ref Des/Silkscreen Top")
		(7 "B.SilkS" user "Ref Des/Silkscreen Bottom")
		(1 "F.Mask" user "Board Geometry/Soldermask Top")
		(3 "B.Mask" user "Board Geometry/Soldermask Bottom")
		(17 "Dwgs.User" user "User.Drawings")
		(19 "Cmts.User" user "User.Comments")
		(21 "Eco1.User" user "User.Eco1")
		(23 "Eco2.User" user "User.Eco2")
		(25 "Edge.Cuts" user "Board Geometry/Outline")
		(27 "Margin" user)
		(31 "F.CrtYd" user "Package Geometry/Place Bound Top")
		(29 "B.CrtYd" user "Package Geometry/Place Bound Bottom")
		(35 "F.Fab" user "Ref Des/Assembly Top")
		(33 "B.Fab" user "Ref Des/Assembly Bottom")
	)
	(footprint ""
		(layer "B.Cu")
		(at 372.1354 -131.0894 -90)
		(property "Reference" "FB3M4"
			(at 0 0 90)
			(layer "B.SilkS")
			(hide yes)
			(effects
				(font
					(size 1.27 1.27)
				)
				(justify mirror)
			)
		)
		(property "Value" ""
			(at 0 0 90)
			(layer "B.Fab")
			(effects
				(font
					(size 1.27 1.27)
				)
				(justify mirror)
			)
		)
		(duplicate_pad_numbers_are_jumpers no)
		(fp_rect
			(start 0.15113 0.47498)
			(end -1.59893 -0.47498)
			(stroke
				(width 0)
				(type default)
			)
			(fill no)
			(layer "B.CrtYd")
		)
		(fp_line
			(start -1.59893 0.47498)
			(end 0.15113 0.47498)
			(stroke
				(width 0.1)
				(type default)
			)
			(layer "B.Fab")
		)
		(fp_line
			(start 0.15113 0.47498)
			(end 0.15113 -0.47498)
			(stroke
				(width 0.1)
				(type default)
			)
			(layer "B.Fab")
		)
		(fp_line
			(start -1.59893 -0.47498)
			(end -1.59893 0.47498)
			(stroke
				(width 0.1)
				(type default)
			)
			(layer "B.Fab")
		)
		(fp_line
			(start 0.15113 -0.47498)
			(end -1.59893 -0.47498)
			(stroke
				(width 0.1)
				(type default)
			)
			(layer "B.Fab")
		)
		(pad "1" smd rect
			(at 0 0 90)
			(size 0.9398 0.9398)
			(layers "B.Cu" "B.Mask" "B.Paste")
			(net "P1V05_PCH_STBY")
		)
		(pad "2" smd rect
			(at -1.4478 0 90)
			(size 0.9398 0.9398)
			(layers "B.Cu" "B.Mask" "B.Paste")
			(net "P1V05_PCH_STBY_ISCLK_PLL")
		)
		(zone
			(layer "B.Cu")
			(hatch none 0.5)
			(connect_pads
				(clearance 0)
			)
			(min_thickness 0.25)
			(keepout
				(tracks not_allowed)
				(vias allowed)
				(pads allowed)
				(copperpour not_allowed)
				(footprints allowed)
			)
			(placement
				(enabled no)
				(sheetname "")
			)
			(fill
				(thermal_gap 0.5)
				(thermal_bridge_width 0.5)
				(island_removal_mode 0)
			)
			(polygon
				(pts
					(xy 371.6655 -131.5593) (xy 372.6053 -131.5593) (xy 372.6053 -132.0673) (xy 371.6655 -132.0673)
				)
			)
		)
		(zone
			(layer "B.Cu")
			(hatch none 0.5)
			(connect_pads
				(clearance 0)
			)
			(min_thickness 0.25)
			(keepout
				(tracks allowed)
				(vias not_allowed)
				(pads allowed)
				(copperpour not_allowed)
				(footprints allowed)
			)
			(placement
				(enabled no)
				(sheetname "")
			)
			(fill
				(thermal_gap 0.5)
				(thermal_bridge_width 0.5)
				(island_removal_mode 0)
			)
			(polygon
				(pts
					(xy 371.6655 -131.5593) (xy 372.6053 -131.5593) (xy 372.6053 -132.0673) (xy 371.6655 -132.0673)
				)
			)
		)
	)
	(footprint ""
		(layer "B.Cu")
		(at 33.620456 -53.157882 90)
		(property "Reference" "C1E6"
			(at 0 0 90)
			(layer "B.SilkS")
			(hide yes)
			(effects
				(font
					(size 1.27 1.27)
				)
				(justify mirror)
			)
		)
		(property "Value" "*"
			(at -1.1811 -2.8194 90)
			(unlocked yes)
			(layer "B.Fab")
			(hide yes)
			(effects
				(font
					(size 1.27 1.016)
					(thickness 0.1524)
				)
				(justify mirror)
			)
		)
		(property "Device Type" "SC1U10V2KX-4-GP_SMD-BCG6-SC1U1A"
			(at -1.1811 -4.3434 90)
			(unlocked yes)
			(layer "B.Fab")
			(hide yes)
			(effects
				(font
					(size 1.27 1.016)
					(thickness 0.1524)
				)
				(justify mirror)
			)
		)
		(duplicate_pad_numbers_are_jumpers no)
		(fp_rect
			(start 0.4318 0.9525)
			(end -0.4318 -0.9525)
			(stroke
				(width 0)
				(type default)
			)
			(fill no)
			(layer "B.CrtYd")
		)
		(fp_rect
			(start 0.4318 0.9525)
			(end -0.4318 -0.9525)
			(stroke
				(width 0)
				(type default)
			)
			(fill no)
			(layer "B.Fab")
		)
		(pad "1" smd custom
			(at 0 -0.4445 270)
			(size 0.1524 0.1524)
			(layers "B.Cu" "B.Mask" "B.Paste")
			(net "P5V_STBY")
			(options
				(clearance outline)
				(anchor circle)
			)
			(primitives
				(gr_poly
					(pts
						(arc
							(start 0.3048 0.2032)
							(mid 0.275042 0.275042)
							(end 0.2032 0.3048)
						)
						(arc
							(start -0.2032 0.3048)
							(mid -0.275042 0.275042)
							(end -0.3048 0.2032)
						)
						(arc
							(start -0.3048 -0.2032)
							(mid -0.275042 -0.275042)
							(end -0.2032 -0.3048)
						)
						(arc
							(start 0.2032 -0.3048)
							(mid 0.275042 -0.275042)
							(end 0.3048 -0.2032)
						)
					)
					(width 0)
					(fill yes)
				)
			)
		)
		(pad "2" smd custom
			(at 0 0.4445 270)
			(size 0.1524 0.1524)
			(layers "B.Cu" "B.Mask" "B.Paste")
			(net "GND")
			(options
				(clearance outline)
				(anchor circle)
			)
			(primitives
				(gr_poly
					(pts
						(arc
							(start 0.3048 0.2032)
							(mid 0.275042 0.275042)
							(end 0.2032 0.3048)
						)
						(arc
							(start -0.2032 0.3048)
							(mid -0.275042 0.275042)
							(end -0.3048 0.2032)
						)
						(arc
							(start -0.3048 -0.2032)
							(mid -0.275042 -0.275042)
							(end -0.2032 -0.3048)
						)
						(arc
							(start 0.2032 -0.3048)
							(mid 0.275042 -0.275042)
							(end 0.3048 -0.2032)
						)
					)
					(width 0)
					(fill yes)
				)
			)
		)
	)
	(footprint ""
		(layer "B.Cu")
		(at 101.3968 -145.0086 90)
		(property "Reference" "C8L6"
			(at -1.848866 0.752348 90)
			(unlocked yes)
			(layer "B.SilkS")
			(effects
				(font
					(size 1.27 0.9652)
					(thickness 0.1524)
				)
				(justify mirror)
			)
		)
		(property "Value" ""
			(at 0 0 90)
			(layer "B.Fab")
			(effects
				(font
					(size 1.27 1.27)
				)
				(justify mirror)
			)
		)
		(duplicate_pad_numbers_are_jumpers no)
		(fp_rect
			(start 0.500126 1.598422)
			(end -0.500126 -0.201422)
			(stroke
				(width 0)
				(type default)
			)
			(fill no)
			(layer "B.CrtYd")
		)
		(fp_line
			(start 0.500126 -0.201422)
			(end -0.500126 -0.201422)
			(stroke
				(width 0.1)
				(type default)
			)
			(layer "B.Fab")
		)
		(fp_line
			(start -0.500126 -0.201422)
			(end -0.500126 1.598422)
			(stroke
				(width 0.1)
				(type default)
			)
			(layer "B.Fab")
		)
		(fp_line
			(start 0.500126 1.598422)
			(end 0.500126 -0.201422)
			(stroke
				(width 0.1)
				(type default)
			)
			(layer "B.Fab")
		)
		(fp_line
			(start -0.500126 1.598422)
			(end 0.500126 1.598422)
			(stroke
				(width 0.1)
				(type default)
			)
			(layer "B.Fab")
		)
		(pad "1" smd rect
			(at 0 0)
			(size 0.889 0.9906)
			(layers "B.Cu" "B.Mask" "B.Paste")
			(net "PVDDQ_KLM")
		)
		(pad "2" smd rect
			(at 0 1.397)
			(size 0.889 0.9906)
			(layers "B.Cu" "B.Mask" "B.Paste")
			(net "GND")
		)
		(zone
			(layer "B.Cu")
			(hatch none 0.5)
			(connect_pads
				(clearance 0)
			)
			(min_thickness 0.25)
			(keepout
				(tracks not_allowed)
				(vias allowed)
				(pads allowed)
				(copperpour not_allowed)
				(footprints allowed)
			)
			(placement
				(enabled no)
				(sheetname "")
			)
			(fill
				(thermal_gap 0.5)
				(thermal_bridge_width 0.5)
				(island_removal_mode 0)
			)
			(polygon
				(pts
					(xy 102.3493 -145.5039) (xy 101.8413 -145.5039) (xy 101.8413 -144.5133) (xy 102.3493 -144.5133)
				)
			)
		)
		(zone
			(layer "B.Cu")
			(hatch none 0.5)
			(connect_pads
				(clearance 0)
			)
			(min_thickness 0.25)
			(keepout
				(tracks allowed)
				(vias not_allowed)
				(pads allowed)
				(copperpour not_allowed)
				(footprints allowed)
			)
			(placement
				(enabled no)
				(sheetname "")
			)
			(fill
				(thermal_gap 0.5)
				(thermal_bridge_width 0.5)
				(island_removal_mode 0)
			)
			(polygon
				(pts
					(xy 102.3493 -145.5039) (xy 101.8413 -145.5039) (xy 101.8413 -144.5133) (xy 102.3493 -144.5133)
				)
			)
		)
	)
)
